# T6G (Grand Teton) — schematic netlist excerpt (pin names and nets, part order shuffled) for the footprints in the layout excerpt that follows; sources: Cadence DE-HDL packaged netlist, KiCad conversion of 04192023_DAF0TMB3IC0_F0TG_MB_C_brd_V02_OCP.brd

PR6815  Q_RES  10K 1% EMPTY  pkg 0402LF  page 364 : A = P0V9_RETIMER_CPU1_TEMP0 ; B = GND
R750  Q_RES  30K 1% CHIP  pkg 0402LF  page 76 : A = GND ; B = CLK_ESPI_CPU0_CLK1

(kicad_pcb
	(version 20260206)
	(generator "pcbnew")
	(generator_version "10.0")
	(general
		(thickness 1.6)
		(legacy_teardrops no)
	)
	(paper "A4")
	(title_block
		(title "04192023_DAF0TMB3IC0_F0TG_MB_C_brd_V02_OCP.brd")
		(comment 1 "Grand Teton / footprints 5335-5336 of 8354")
	)
	(layers
		(0 "F.Cu" signal "TOP")
		(4 "In1.Cu" signal "GND")
		(6 "In2.Cu" signal "IN1")
		(8 "In3.Cu" signal "GND1")
		(10 "In4.Cu" signal "IN2")
		(12 "In5.Cu" signal "GND2")
		(14 "In6.Cu" signal "IN3")
		(16 "In7.Cu" signal "GND3")
		(18 "In8.Cu" signal "VCC")
		(20 "In9.Cu" signal "VCC1")
		(22 "In10.Cu" signal "GND4")
		(24 "In11.Cu" signal "IN4")
		(26 "In12.Cu" signal "GND5")
		(28 "In13.Cu" signal "IN5")
		(30 "In14.Cu" signal "GND6")
		(32 "In15.Cu" signal "IN6")
		(34 "In16.Cu" signal "GND7")
		(2 "B.Cu" signal "BOTTOM")
		(9 "F.Adhes" user "F.Adhesive")
		(11 "B.Adhes" user "B.Adhesive")
		(13 "F.Paste" user "Package Geometry/Pastemask Top")
		(15 "B.Paste" user "Package Geometry/Pastemask Bottom")
		(5 "F.SilkS" user "Ref Des/Silkscreen Top")
		(7 "B.SilkS" user "Ref Des/Silkscreen Bottom")
		(1 "F.Mask" user "Board Geometry/Soldermask Top")
		(3 "B.Mask" user "Board Geometry/Soldermask Bottom")
		(17 "Dwgs.User" user "User.Drawings")
		(19 "Cmts.User" user "User.Comments")
		(21 "Eco1.User" user "User.Eco1")
		(23 "Eco2.User" user "User.Eco2")
		(25 "Edge.Cuts" user "Board Geometry/Outline")
		(27 "Margin" user)
		(31 "F.CrtYd" user "Package Geometry/Place Bound Top")
		(29 "B.CrtYd" user "Package Geometry/Place Bound Bottom")
		(35 "F.Fab" user "Ref Des/Assembly Top")
		(33 "B.Fab" user "Ref Des/Assembly Bottom")
	)
	(footprint ""
		(layer "B.Cu")
		(at 10.066782 -412.291784)
		(property "Reference" "PR6815"
			(at 0 0 0)
			(layer "B.SilkS")
			(hide yes)
			(effects
				(font
					(size 1.27 1.27)
				)
				(justify mirror)
			)
		)
		(property "Value" ""
			(at 0 0 0)
			(layer "B.Fab")
			(effects
				(font
					(size 1.27 1.27)
				)
				(justify mirror)
			)
		)
		(duplicate_pad_numbers_are_jumpers no)
		(fp_line
			(start -0.7874 -0.4064)
			(end -0.7874 0.4064)
			(stroke
				(width 0.1524)
				(type default)
			)
			(layer "B.SilkS")
		)
		(fp_line
			(start -0.7874 0.4064)
			(end 0.7874 0.4064)
			(stroke
				(width 0.1524)
				(type default)
			)
			(layer "B.SilkS")
		)
		(fp_line
			(start 0.7874 -0.4064)
			(end -0.7874 -0.4064)
			(stroke
				(width 0.1524)
				(type default)
			)
			(layer "B.SilkS")
		)
		(fp_line
			(start 0.7874 0.4064)
			(end 0.7874 -0.4064)
			(stroke
				(width 0.1524)
				(type default)
			)
			(layer "B.SilkS")
		)
		(fp_line
			(start -0.67945 -0.3048)
			(end -0.67945 0.3048)
			(stroke
				(width 0.1)
				(type default)
			)
			(layer "B.Fab")
		)
		(fp_line
			(start -0.67945 0.3048)
			(end -0.120396 0.3048)
			(stroke
				(width 0.1)
				(type default)
			)
			(layer "B.Fab")
		)
		(fp_line
			(start -0.12065 -0.3048)
			(end -0.67945 -0.3048)
			(stroke
				(width 0.1)
				(type default)
			)
			(layer "B.Fab")
		)
		(fp_line
			(start -0.12065 -0.2794)
			(end -0.12065 -0.3048)
			(stroke
				(width 0.1)
				(type default)
			)
			(layer "B.Fab")
		)
		(fp_line
			(start -0.120396 0.2794)
			(end 0.12065 0.2794)
			(stroke
				(width 0.1)
				(type default)
			)
			(layer "B.Fab")
		)
		(fp_line
			(start -0.120396 0.3048)
			(end -0.120396 0.2794)
			(stroke
				(width 0.1)
				(type default)
			)
			(layer "B.Fab")
		)
		(fp_line
			(start 0.12065 -0.305054)
			(end 0.12065 -0.2794)
			(stroke
				(width 0.1)
				(type default)
			)
			(layer "B.Fab")
		)
		(fp_line
			(start 0.12065 -0.2794)
			(end -0.12065 -0.2794)
			(stroke
				(width 0.1)
				(type default)
			)
			(layer "B.Fab")
		)
		(fp_line
			(start 0.12065 0.2794)
			(end 0.12065 0.3048)
			(stroke
				(width 0.1)
				(type default)
			)
			(layer "B.Fab")
		)
		(fp_line
			(start 0.12065 0.3048)
			(end 0.67945 0.3048)
			(stroke
				(width 0.1)
				(type default)
			)
			(layer "B.Fab")
		)
		(fp_line
			(start 0.67945 -0.305054)
			(end 0.12065 -0.305054)
			(stroke
				(width 0.1)
				(type default)
			)
			(layer "B.Fab")
		)
		(fp_line
			(start 0.67945 0.3048)
			(end 0.67945 -0.305054)
			(stroke
				(width 0.1)
				(type default)
			)
			(layer "B.Fab")
		)
		(pad "1" smd circle
			(at 0.40005 0 180)
			(size 0 0)
			(layers "B.Cu" "B.Mask" "B.Paste")
			(net "P0V9_RETIMER_CPU1_TEMP0")
		)
		(pad "2" smd circle
			(at -0.40005 0 180)
			(size 0 0)
			(layers "B.Cu" "B.Mask" "B.Paste")
			(net "GND")
		)
	)
	(footprint ""
		(layer "B.Cu")
		(at 393.637008 -321.179952)
		(property "Reference" "R750"
			(at 0 0 0)
			(layer "B.SilkS")
			(hide yes)
			(effects
				(font
					(size 1.27 1.27)
				)
				(justify mirror)
			)
		)
		(property "Value" ""
			(at 0 0 0)
			(layer "B.Fab")
			(effects
				(font
					(size 1.27 1.27)
				)
				(justify mirror)
			)
		)
		(duplicate_pad_numbers_are_jumpers no)
		(fp_line
			(start -0.7874 -0.4064)
			(end -0.7874 0.4064)
			(stroke
				(width 0.1524)
				(type default)
			)
			(layer "B.SilkS")
		)
		(fp_line
			(start -0.7874 0.4064)
			(end 0.7874 0.4064)
			(stroke
				(width 0.1524)
				(type default)
			)
			(layer "B.SilkS")
		)
		(fp_line
			(start 0.7874 -0.4064)
			(end -0.7874 -0.4064)
			(stroke
				(width 0.1524)
				(type default)
			)
			(layer "B.SilkS")
		)
		(fp_line
			(start 0.7874 0.4064)
			(end 0.7874 -0.4064)
			(stroke
				(width 0.1524)
				(type default)
			)
			(layer "B.SilkS")
		)
		(fp_line
			(start -0.67945 -0.3048)
			(end -0.67945 0.3048)
			(stroke
				(width 0.1)
				(type default)
			)
			(layer "B.Fab")
		)
		(fp_line
			(start -0.67945 0.3048)
			(end -0.120396 0.3048)
			(stroke
				(width 0.1)
				(type default)
			)
			(layer "B.Fab")
		)
		(fp_line
			(start -0.12065 -0.3048)
			(end -0.67945 -0.3048)
			(stroke
				(width 0.1)
				(type default)
			)
			(layer "B.Fab")
		)
		(fp_line
			(start -0.12065 -0.2794)
			(end -0.12065 -0.3048)
			(stroke
				(width 0.1)
				(type default)
			)
			(layer "B.Fab")
		)
		(fp_line
			(start -0.120396 0.2794)
			(end 0.12065 0.2794)
			(stroke
				(width 0.1)
				(type default)
			)
			(layer "B.Fab")
		)
		(fp_line
			(start -0.120396 0.3048)
			(end -0.120396 0.2794)
			(stroke
				(width 0.1)
				(type default)
			)
			(layer "B.Fab")
		)
		(fp_line
			(start 0.12065 -0.305054)
			(end 0.12065 -0.2794)
			(stroke
				(width 0.1)
				(type default)
			)
			(layer "B.Fab")
		)
		(fp_line
			(start 0.12065 -0.2794)
			(end -0.12065 -0.2794)
			(stroke
				(width 0.1)
				(type default)
			)
			(layer "B.Fab")
		)
		(fp_line
			(start 0.12065 0.2794)
			(end 0.12065 0.3048)
			(stroke
				(width 0.1)
				(type default)
			)
			(layer "B.Fab")
		)
		(fp_line
			(start 0.12065 0.3048)
			(end 0.67945 0.3048)
			(stroke
				(width 0.1)
				(type default)
			)
			(layer "B.Fab")
		)
		(fp_line
			(start 0.67945 -0.305054)
			(end 0.12065 -0.305054)
			(stroke
				(width 0.1)
				(type default)
			)
			(layer "B.Fab")
		)
		(fp_line
			(start 0.67945 0.3048)
			(end 0.67945 -0.305054)
			(stroke
				(width 0.1)
				(type default)
			)
			(layer "B.Fab")
		)
		(pad "1" smd circle
			(at 0.40005 0 180)
			(size 0 0)
			(layers "B.Cu" "B.Mask" "B.Paste")
			(net "GND")
		)
		(pad "2" smd circle
			(at -0.40005 0 180)
			(size 0 0)
			(layers "B.Cu" "B.Mask" "B.Paste")
			(net "CLK_ESPI_CPU0_CLK1")
		)
	)
)
